(kicad_pcb
	(version 20260206)
	(generator "pcbnew")
	(generator_version "10.0")
	(general
		(thickness 1.6)
		(legacy_teardrops no)
	)
	(paper "A4")
	(title_block
		(title "12092022_DA0F0TFB6D0_F0T_FAN_BOARD_MP5048_D_brd_v02_OCP.brd")
		(comment 1 "Grand Teton / footprints 671-676 of 924")
	)
	(layers
		(0 "F.Cu" signal "TOP")
		(4 "In1.Cu" signal "GND")
		(6 "In2.Cu" signal "IN1")
		(8 "In3.Cu" signal "IN2")
		(10 "In4.Cu" signal "GND1")
		(2 "B.Cu" signal "BOTTOM")
		(9 "F.Adhes" user "F.Adhesive")
		(11 "B.Adhes" user "B.Adhesive")
		(13 "F.Paste" user "Package Geometry/Pastemask Top")
		(15 "B.Paste" user "Package Geometry/Pastemask Bottom")
		(5 "F.SilkS" user "Ref Des/Silkscreen Top")
		(7 "B.SilkS" user "Ref Des/Silkscreen Bottom")
		(1 "F.Mask" user "Board Geometry/Soldermask Top")
		(3 "B.Mask" user "Board Geometry/Soldermask Bottom")
		(17 "Dwgs.User" user "User.Drawings")
		(19 "Cmts.User" user "User.Comments")
		(21 "Eco1.User" user "User.Eco1")
		(23 "Eco2.User" user "User.Eco2")
		(25 "Edge.Cuts" user "Board Geometry/Outline")
		(27 "Margin" user)
		(31 "F.CrtYd" user "Package Geometry/Place Bound Top")
		(29 "B.CrtYd" user "Package Geometry/Place Bound Bottom")
		(35 "F.Fab" user "Ref Des/Assembly Top")
		(33 "B.Fab" user "Ref Des/Assembly Bottom")
	)
	(footprint ""
		(layer "F.Cu")
		(at 34.798 -193.548)
		(property "Reference" "C2031"
			(at 0 0 0)
			(layer "F.SilkS")
			(hide yes)
			(effects
				(font
					(size 1.27 1.27)
				)
			)
		)
		(property "Value" ""
			(at 0 0 0)
			(layer "F.Fab")
			(effects
				(font
					(size 1.27 1.27)
				)
			)
		)
		(duplicate_pad_numbers_are_jumpers no)
		(fp_line
			(start -0.7874 -0.4064)
			(end 0.7874 -0.4064)
			(stroke
				(width 0.1524)
				(type default)
			)
			(layer "F.SilkS")
		)
		(fp_line
			(start -0.7874 0.4064)
			(end -0.7874 -0.4064)
			(stroke
				(width 0.1524)
				(type default)
			)
			(layer "F.SilkS")
		)
		(fp_line
			(start 0.7874 -0.4064)
			(end 0.7874 0.4064)
			(stroke
				(width 0.1524)
				(type default)
			)
			(layer "F.SilkS")
		)
		(fp_line
			(start 0.7874 0.4064)
			(end -0.7874 0.4064)
			(stroke
				(width 0.1524)
				(type default)
			)
			(layer "F.SilkS")
		)
		(fp_line
			(start -0.67945 -0.305054)
			(end -0.12065 -0.305054)
			(stroke
				(width 0.1)
				(type default)
			)
			(layer "F.Fab")
		)
		(fp_line
			(start -0.67945 0.3048)
			(end -0.67945 -0.305054)
			(stroke
				(width 0.1)
				(type default)
			)
			(layer "F.Fab")
		)
		(fp_line
			(start -0.12065 -0.305054)
			(end -0.12065 -0.2794)
			(stroke
				(width 0.1)
				(type default)
			)
			(layer "F.Fab")
		)
		(fp_line
			(start -0.12065 -0.2794)
			(end 0.12065 -0.2794)
			(stroke
				(width 0.1)
				(type default)
			)
			(layer "F.Fab")
		)
		(fp_line
			(start -0.12065 0.2794)
			(end -0.12065 0.3048)
			(stroke
				(width 0.1)
				(type default)
			)
			(layer "F.Fab")
		)
		(fp_line
			(start -0.12065 0.3048)
			(end -0.67945 0.3048)
			(stroke
				(width 0.1)
				(type default)
			)
			(layer "F.Fab")
		)
		(fp_line
			(start 0.120396 0.2794)
			(end -0.12065 0.2794)
			(stroke
				(width 0.1)
				(type default)
			)
			(layer "F.Fab")
		)
		(fp_line
			(start 0.120396 0.3048)
			(end 0.120396 0.2794)
			(stroke
				(width 0.1)
				(type default)
			)
			(layer "F.Fab")
		)
		(fp_line
			(start 0.12065 -0.3048)
			(end 0.67945 -0.3048)
			(stroke
				(width 0.1)
				(type default)
			)
			(layer "F.Fab")
		)
		(fp_line
			(start 0.12065 -0.2794)
			(end 0.12065 -0.3048)
			(stroke
				(width 0.1)
				(type default)
			)
			(layer "F.Fab")
		)
		(fp_line
			(start 0.67945 -0.3048)
			(end 0.67945 0.3048)
			(stroke
				(width 0.1)
				(type default)
			)
			(layer "F.Fab")
		)
		(fp_line
			(start 0.67945 0.3048)
			(end 0.120396 0.3048)
			(stroke
				(width 0.1)
				(type default)
			)
			(layer "F.Fab")
		)
		(pad "1" smd circle
			(at -0.40005 0)
			(size 0 0)
			(layers "F.Cu" "F.Mask" "F.Paste")
			(net "FAN_1_TACH_OL_R")
		)
		(pad "2" smd circle
			(at 0.40005 0)
			(size 0 0)
			(layers "F.Cu" "F.Mask" "F.Paste")
			(net "GND")
		)
	)
	(footprint ""
		(layer "F.Cu")
		(at 27.432 -187.452 180)
		(property "Reference" "R5492"
			(at 0 0 180)
			(layer "F.SilkS")
			(hide yes)
			(effects
				(font
					(size 1.27 1.27)
				)
			)
		)
		(property "Value" ""
			(at 0 0 180)
			(layer "F.Fab")
			(effects
				(font
					(size 1.27 1.27)
				)
			)
		)
		(duplicate_pad_numbers_are_jumpers no)
		(fp_line
			(start 0.7874 0.4064)
			(end -0.7874 0.4064)
			(stroke
				(width 0.1524)
				(type default)
			)
			(layer "F.SilkS")
		)
		(fp_line
			(start 0.7874 -0.4064)
			(end 0.7874 0.4064)
			(stroke
				(width 0.1524)
				(type default)
			)
			(layer "F.SilkS")
		)
		(fp_line
			(start -0.7874 0.4064)
			(end -0.7874 -0.4064)
			(stroke
				(width 0.1524)
				(type default)
			)
			(layer "F.SilkS")
		)
		(fp_line
			(start -0.7874 -0.4064)
			(end 0.7874 -0.4064)
			(stroke
				(width 0.1524)
				(type default)
			)
			(layer "F.SilkS")
		)
		(fp_line
			(start 0.67945 0.3048)
			(end 0.120396 0.3048)
			(stroke
				(width 0.1)
				(type default)
			)
			(layer "F.Fab")
		)
		(fp_line
			(start 0.67945 -0.3048)
			(end 0.67945 0.3048)
			(stroke
				(width 0.1)
				(type default)
			)
			(layer "F.Fab")
		)
		(fp_line
			(start 0.12065 -0.2794)
			(end 0.12065 -0.3048)
			(stroke
				(width 0.1)
				(type default)
			)
			(layer "F.Fab")
		)
		(fp_line
			(start 0.12065 -0.3048)
			(end 0.67945 -0.3048)
			(stroke
				(width 0.1)
				(type default)
			)
			(layer "F.Fab")
		)
		(fp_line
			(start 0.120396 0.3048)
			(end 0.120396 0.2794)
			(stroke
				(width 0.1)
				(type default)
			)
			(layer "F.Fab")
		)
		(fp_line
			(start 0.120396 0.2794)
			(end -0.12065 0.2794)
			(stroke
				(width 0.1)
				(type default)
			)
			(layer "F.Fab")
		)
		(fp_line
			(start -0.12065 0.3048)
			(end -0.67945 0.3048)
			(stroke
				(width 0.1)
				(type default)
			)
			(layer "F.Fab")
		)
		(fp_line
			(start -0.12065 0.2794)
			(end -0.12065 0.3048)
			(stroke
				(width 0.1)
				(type default)
			)
			(layer "F.Fab")
		)
		(fp_line
			(start -0.12065 -0.2794)
			(end 0.12065 -0.2794)
			(stroke
				(width 0.1)
				(type default)
			)
			(layer "F.Fab")
		)
		(fp_line
			(start -0.12065 -0.305054)
			(end -0.12065 -0.2794)
			(stroke
				(width 0.1)
				(type default)
			)
			(layer "F.Fab")
		)
		(fp_line
			(start -0.67945 0.3048)
			(end -0.67945 -0.305054)
			(stroke
				(width 0.1)
				(type default)
			)
			(layer "F.Fab")
		)
		(fp_line
			(start -0.67945 -0.305054)
			(end -0.12065 -0.305054)
			(stroke
				(width 0.1)
				(type default)
			)
			(layer "F.Fab")
		)
		(pad "1" smd circle
			(at -0.40005 0 180)
			(size 0 0)
			(layers "F.Cu" "F.Mask" "F.Paste")
			(net "P52V_FAN_5_BUFF_EN")
		)
		(pad "2" smd circle
			(at 0.40005 0 180)
			(size 0 0)
			(layers "F.Cu" "F.Mask" "F.Paste")
			(net "P52V_FAN_5_BUFF_EN_R")
		)
	)
	(footprint ""
		(layer "F.Cu")
		(at 3.81 -130.937)
		(property "Reference" "R5571"
			(at 0 0 0)
			(layer "F.SilkS")
			(hide yes)
			(effects
				(font
					(size 1.27 1.27)
				)
			)
		)
		(property "Value" ""
			(at 0 0 0)
			(layer "F.Fab")
			(effects
				(font
					(size 1.27 1.27)
				)
			)
		)
		(duplicate_pad_numbers_are_jumpers no)
		(fp_line
			(start -0.7874 -0.4064)
			(end 0.7874 -0.4064)
			(stroke
				(width 0.1524)
				(type default)
			)
			(layer "F.SilkS")
		)
		(fp_line
			(start -0.7874 0.4064)
			(end -0.7874 -0.4064)
			(stroke
				(width 0.1524)
				(type default)
			)
			(layer "F.SilkS")
		)
		(fp_line
			(start 0.7874 -0.4064)
			(end 0.7874 0.4064)
			(stroke
				(width 0.1524)
				(type default)
			)
			(layer "F.SilkS")
		)
		(fp_line
			(start 0.7874 0.4064)
			(end -0.7874 0.4064)
			(stroke
				(width 0.1524)
				(type default)
			)
			(layer "F.SilkS")
		)
		(fp_line
			(start -0.67945 -0.305054)
			(end -0.12065 -0.305054)
			(stroke
				(width 0.1)
				(type default)
			)
			(layer "F.Fab")
		)
		(fp_line
			(start -0.67945 0.3048)
			(end -0.67945 -0.305054)
			(stroke
				(width 0.1)
				(type default)
			)
			(layer "F.Fab")
		)
		(fp_line
			(start -0.12065 -0.305054)
			(end -0.12065 -0.2794)
			(stroke
				(width 0.1)
				(type default)
			)
			(layer "F.Fab")
		)
		(fp_line
			(start -0.12065 -0.2794)
			(end 0.12065 -0.2794)
			(stroke
				(width 0.1)
				(type default)
			)
			(layer "F.Fab")
		)
		(fp_line
			(start -0.12065 0.2794)
			(end -0.12065 0.3048)
			(stroke
				(width 0.1)
				(type default)
			)
			(layer "F.Fab")
		)
		(fp_line
			(start -0.12065 0.3048)
			(end -0.67945 0.3048)
			(stroke
				(width 0.1)
				(type default)
			)
			(layer "F.Fab")
		)
		(fp_line
			(start 0.120396 0.2794)
			(end -0.12065 0.2794)
			(stroke
				(width 0.1)
				(type default)
			)
			(layer "F.Fab")
		)
		(fp_line
			(start 0.120396 0.3048)
			(end 0.120396 0.2794)
			(stroke
				(width 0.1)
				(type default)
			)
			(layer "F.Fab")
		)
		(fp_line
			(start 0.12065 -0.3048)
			(end 0.67945 -0.3048)
			(stroke
				(width 0.1)
				(type default)
			)
			(layer "F.Fab")
		)
		(fp_line
			(start 0.12065 -0.2794)
			(end 0.12065 -0.3048)
			(stroke
				(width 0.1)
				(type default)
			)
			(layer "F.Fab")
		)
		(fp_line
			(start 0.67945 -0.3048)
			(end 0.67945 0.3048)
			(stroke
				(width 0.1)
				(type default)
			)
			(layer "F.Fab")
		)
		(fp_line
			(start 0.67945 0.3048)
			(end 0.120396 0.3048)
			(stroke
				(width 0.1)
				(type default)
			)
			(layer "F.Fab")
		)
		(pad "1" smd circle
			(at -0.40005 0)
			(size 0 0)
			(layers "F.Cu" "F.Mask" "F.Paste")
			(net "GND")
		)
		(pad "2" smd circle
			(at 0.40005 0)
			(size 0 0)
			(layers "F.Cu" "F.Mask" "F.Paste")
			(net "U404_ADD1")
		)
	)
	(footprint ""
		(layer "F.Cu")
		(at 16.51 -197.739 180)
		(property "Reference" "C2046"
			(at 0 0 180)
			(layer "F.SilkS")
			(hide yes)
			(effects
				(font
					(size 1.27 1.27)
				)
			)
		)
		(property "Value" ""
			(at 0 0 180)
			(layer "F.Fab")
			(effects
				(font
					(size 1.27 1.27)
				)
			)
		)
		(duplicate_pad_numbers_are_jumpers no)
		(fp_line
			(start 0.7874 0.4064)
			(end -0.7874 0.4064)
			(stroke
				(width 0.1524)
				(type default)
			)
			(layer "F.SilkS")
		)
		(fp_line
			(start 0.7874 -0.4064)
			(end 0.7874 0.4064)
			(stroke
				(width 0.1524)
				(type default)
			)
			(layer "F.SilkS")
		)
		(fp_line
			(start -0.7874 0.4064)
			(end -0.7874 -0.4064)
			(stroke
				(width 0.1524)
				(type default)
			)
			(layer "F.SilkS")
		)
		(fp_line
			(start -0.7874 -0.4064)
			(end 0.7874 -0.4064)
			(stroke
				(width 0.1524)
				(type default)
			)
			(layer "F.SilkS")
		)
		(fp_line
			(start 0.67945 0.3048)
			(end 0.120396 0.3048)
			(stroke
				(width 0.1)
				(type default)
			)
			(layer "F.Fab")
		)
		(fp_line
			(start 0.67945 -0.3048)
			(end 0.67945 0.3048)
			(stroke
				(width 0.1)
				(type default)
			)
			(layer "F.Fab")
		)
		(fp_line
			(start 0.12065 -0.2794)
			(end 0.12065 -0.3048)
			(stroke
				(width 0.1)
				(type default)
			)
			(layer "F.Fab")
		)
		(fp_line
			(start 0.12065 -0.3048)
			(end 0.67945 -0.3048)
			(stroke
				(width 0.1)
				(type default)
			)
			(layer "F.Fab")
		)
		(fp_line
			(start 0.120396 0.3048)
			(end 0.120396 0.2794)
			(stroke
				(width 0.1)
				(type default)
			)
			(layer "F.Fab")
		)
		(fp_line
			(start 0.120396 0.2794)
			(end -0.12065 0.2794)
			(stroke
				(width 0.1)
				(type default)
			)
			(layer "F.Fab")
		)
		(fp_line
			(start -0.12065 0.3048)
			(end -0.67945 0.3048)
			(stroke
				(width 0.1)
				(type default)
			)
			(layer "F.Fab")
		)
		(fp_line
			(start -0.12065 0.2794)
			(end -0.12065 0.3048)
			(stroke
				(width 0.1)
				(type default)
			)
			(layer "F.Fab")
		)
		(fp_line
			(start -0.12065 -0.2794)
			(end 0.12065 -0.2794)
			(stroke
				(width 0.1)
				(type default)
			)
			(layer "F.Fab")
		)
		(fp_line
			(start -0.12065 -0.305054)
			(end -0.12065 -0.2794)
			(stroke
				(width 0.1)
				(type default)
			)
			(layer "F.Fab")
		)
		(fp_line
			(start -0.67945 0.3048)
			(end -0.67945 -0.305054)
			(stroke
				(width 0.1)
				(type default)
			)
			(layer "F.Fab")
		)
		(fp_line
			(start -0.67945 -0.305054)
			(end -0.12065 -0.305054)
			(stroke
				(width 0.1)
				(type default)
			)
			(layer "F.Fab")
		)
		(pad "1" smd circle
			(at -0.40005 0 180)
			(size 0 0)
			(layers "F.Cu" "F.Mask" "F.Paste")
			(net "FAN_6_TACH_IL_R")
		)
		(pad "2" smd circle
			(at 0.40005 0 180)
			(size 0 0)
			(layers "F.Cu" "F.Mask" "F.Paste")
			(net "GND")
		)
	)
	(footprint ""
		(layer "F.Cu")
		(at 19.304 -34.925 180)
		(property "Reference" "Q13"
			(at 1.39446 2.44221 0)
			(unlocked yes)
			(layer "F.SilkS")
			(effects
				(font
					(size 0.7874 0.5842)
					(thickness 0.1524)
				)
				(justify left)
			)
		)
		(property "Value" ""
			(at 0 0 180)
			(layer "F.Fab")
			(effects
				(font
					(size 1.27 1.27)
				)
			)
		)
		(duplicate_pad_numbers_are_jumpers no)
		(fp_line
			(start 1.905 1.651)
			(end -1.905 1.651)
			(stroke
				(width 0.1524)
				(type default)
			)
			(layer "F.SilkS")
		)
		(fp_line
			(start 1.905 -1.651)
			(end 1.905 1.651)
			(stroke
				(width 0.1524)
				(type default)
			)
			(layer "F.SilkS")
		)
		(fp_line
			(start -1.905 1.651)
			(end -1.905 -1.651)
			(stroke
				(width 0.1524)
				(type default)
			)
			(layer "F.SilkS")
		)
		(fp_line
			(start -1.905 -1.651)
			(end 1.905 -1.651)
			(stroke
				(width 0.1524)
				(type default)
			)
			(layer "F.SilkS")
		)
		(fp_line
			(start 1.249934 0.219964)
			(end 0.6985 0.219964)
			(stroke
				(width 0.1)
				(type default)
			)
			(layer "F.Fab")
		)
		(fp_line
			(start 1.249934 -0.219964)
			(end 1.249934 0.219964)
			(stroke
				(width 0.1)
				(type default)
			)
			(layer "F.Fab")
		)
		(fp_line
			(start 0.6985 1.524)
			(end -0.6985 1.524)
			(stroke
				(width 0.1)
				(type default)
			)
			(layer "F.Fab")
		)
		(fp_line
			(start 0.6985 0.219964)
			(end 0.6985 1.524)
			(stroke
				(width 0.1)
				(type default)
			)
			(layer "F.Fab")
		)
		(fp_line
			(start 0.6985 -0.219964)
			(end 1.249934 -0.219964)
			(stroke
				(width 0.1)
				(type default)
			)
			(layer "F.Fab")
		)
		(fp_line
			(start 0.6985 -1.524)
			(end 0.6985 -0.219964)
			(stroke
				(width 0.1)
				(type default)
			)
			(layer "F.Fab")
		)
		(fp_line
			(start -0.6985 1.524)
			(end -0.6985 1.169924)
			(stroke
				(width 0.1)
				(type default)
			)
			(layer "F.Fab")
		)
		(fp_line
			(start -0.6985 1.169924)
			(end -1.249934 1.169924)
			(stroke
				(width 0.1)
				(type default)
			)
			(layer "F.Fab")
		)
		(fp_line
			(start -0.6985 0.729996)
			(end -0.6985 -0.729996)
			(stroke
				(width 0.1)
				(type default)
			)
			(layer "F.Fab")
		)
		(fp_line
			(start -0.6985 -0.729996)
			(end -1.249934 -0.729996)
			(stroke
				(width 0.1)
				(type default)
			)
			(layer "F.Fab")
		)
		(fp_line
			(start -0.6985 -1.169924)
			(end -0.6985 -1.524)
			(stroke
				(width 0.1)
				(type default)
			)
			(layer "F.Fab")
		)
		(fp_line
			(start -0.6985 -1.524)
			(end 0.6985 -1.524)
			(stroke
				(width 0.1)
				(type default)
			)
			(layer "F.Fab")
		)
		(fp_line
			(start -1.249934 1.169924)
			(end -1.249934 0.729996)
			(stroke
				(width 0.1)
				(type default)
			)
			(layer "F.Fab")
		)
		(fp_line
			(start -1.249934 0.729996)
			(end -0.6985 0.729996)
			(stroke
				(width 0.1)
				(type default)
			)
			(layer "F.Fab")
		)
		(fp_line
			(start -1.249934 -0.729996)
			(end -1.249934 -1.169924)
			(stroke
				(width 0.1)
				(type default)
			)
			(layer "F.Fab")
		)
		(fp_line
			(start -1.249934 -1.169924)
			(end -0.6985 -1.169924)
			(stroke
				(width 0.1)
				(type default)
			)
			(layer "F.Fab")
		)
		(fp_rect
			(start 0.6985 -1.524)
			(end -0.6985 1.524)
			(stroke
				(width 0)
				(type default)
			)
			(fill no)
			(layer "F.Fab")
		)
		(pad "D" smd rect
			(at 1.1176 0 90)
			(size 1.016 1.27)
			(layers "F.Cu" "F.Mask" "F.Paste")
			(net "P12V_LED_FAN4")
		)
		(pad "G" smd rect
			(at -1.1176 -1.016 90)
			(size 1.016 1.27)
			(layers "F.Cu" "F.Mask" "F.Paste")
			(net "U409_D1")
		)
		(pad "S" smd rect
			(at -1.1176 1.016 90)
			(size 1.016 1.27)
			(layers "F.Cu" "F.Mask" "F.Paste")
			(net "P12V_LED")
		)
	)
	(footprint ""
		(layer "F.Cu")
		(at 25.654 -141.605 -90)
		(property "Reference" "R5279"
			(at 0 0 270)
			(layer "F.SilkS")
			(hide yes)
			(effects
				(font
					(size 1.27 1.27)
				)
			)
		)
		(property "Value" ""
			(at 0 0 270)
			(layer "F.Fab")
			(effects
				(font
					(size 1.27 1.27)
				)
			)
		)
		(duplicate_pad_numbers_are_jumpers no)
		(fp_line
			(start -0.7874 0.4064)
			(end -0.7874 -0.4064)
			(stroke
				(width 0.1524)
				(type default)
			)
			(layer "F.SilkS")
		)
		(fp_line
			(start 0.7874 0.4064)
			(end -0.7874 0.4064)
			(stroke
				(width 0.1524)
				(type default)
			)
			(layer "F.SilkS")
		)
		(fp_line
			(start -0.7874 -0.4064)
			(end 0.7874 -0.4064)
			(stroke
				(width 0.1524)
				(type default)
			)
			(layer "F.SilkS")
		)
		(fp_line
			(start 0.7874 -0.4064)
			(end 0.7874 0.4064)
			(stroke
				(width 0.1524)
				(type default)
			)
			(layer "F.SilkS")
		)
		(fp_line
			(start -0.67945 0.3048)
			(end -0.67945 -0.305054)
			(stroke
				(width 0.1)
				(type default)
			)
			(layer "F.Fab")
		)
		(fp_line
			(start -0.12065 0.3048)
			(end -0.67945 0.3048)
			(stroke
				(width 0.1)
				(type default)
			)
			(layer "F.Fab")
		)
		(fp_line
			(start 0.120396 0.3048)
			(end 0.120396 0.2794)
			(stroke
				(width 0.1)
				(type default)
			)
			(layer "F.Fab")
		)
		(fp_line
			(start 0.67945 0.3048)
			(end 0.120396 0.3048)
			(stroke
				(width 0.1)
				(type default)
			)
			(layer "F.Fab")
		)
		(fp_line
			(start -0.12065 0.2794)
			(end -0.12065 0.3048)
			(stroke
				(width 0.1)
				(type default)
			)
			(layer "F.Fab")
		)
		(fp_line
			(start 0.120396 0.2794)
			(end -0.12065 0.2794)
			(stroke
				(width 0.1)
				(type default)
			)
			(layer "F.Fab")
		)
		(fp_line
			(start -0.12065 -0.2794)
			(end 0.12065 -0.2794)
			(stroke
				(width 0.1)
				(type default)
			)
			(layer "F.Fab")
		)
		(fp_line
			(start 0.12065 -0.2794)
			(end 0.12065 -0.3048)
			(stroke
				(width 0.1)
				(type default)
			)
			(layer "F.Fab")
		)
		(fp_line
			(start 0.12065 -0.3048)
			(end 0.67945 -0.3048)
			(stroke
				(width 0.1)
				(type default)
			)
			(layer "F.Fab")
		)
		(fp_line
			(start 0.67945 -0.3048)
			(end 0.67945 0.3048)
			(stroke
				(width 0.1)
				(type default)
			)
			(layer "F.Fab")
		)
		(fp_line
			(start -0.67945 -0.305054)
			(end -0.12065 -0.305054)
			(stroke
				(width 0.1)
				(type default)
			)
			(layer "F.Fab")
		)
		(fp_line
			(start -0.12065 -0.305054)
			(end -0.12065 -0.2794)
			(stroke
				(width 0.1)
				(type default)
			)
			(layer "F.Fab")
		)
		(pad "1" smd circle
			(at -0.40005 0 270)
			(size 0 0)
			(layers "F.Cu" "F.Mask" "F.Paste")
			(net "SMB_FAN1_R_SDA")
		)
		(pad "2" smd circle
			(at 0.40005 0 270)
			(size 0 0)
			(layers "F.Cu" "F.Mask" "F.Paste")
			(net "P3V3_AUX")
		)
	)
)
